(kicad_pcb
	(version 20260206)
	(generator "pcbnew")
	(generator_version "10.0")
	(general
		(thickness 1.6)
		(legacy_teardrops no)
	)
	(paper "A4")
	(title_block
		(title "04192023_DAF0TMB3IC0_F0TG_MB_C_brd_V02_OCP.brd")
		(comment 1 "Grand Teton / footprints 4532-4538 of 8354")
	)
	(layers
		(0 "F.Cu" signal "TOP")
		(4 "In1.Cu" signal "GND")
		(6 "In2.Cu" signal "IN1")
		(8 "In3.Cu" signal "GND1")
		(10 "In4.Cu" signal "IN2")
		(12 "In5.Cu" signal "GND2")
		(14 "In6.Cu" signal "IN3")
		(16 "In7.Cu" signal "GND3")
		(18 "In8.Cu" signal "VCC")
		(20 "In9.Cu" signal "VCC1")
		(22 "In10.Cu" signal "GND4")
		(24 "In11.Cu" signal "IN4")
		(26 "In12.Cu" signal "GND5")
		(28 "In13.Cu" signal "IN5")
		(30 "In14.Cu" signal "GND6")
		(32 "In15.Cu" signal "IN6")
		(34 "In16.Cu" signal "GND7")
		(2 "B.Cu" signal "BOTTOM")
		(9 "F.Adhes" user "F.Adhesive")
		(11 "B.Adhes" user "B.Adhesive")
		(13 "F.Paste" user "Package Geometry/Pastemask Top")
		(15 "B.Paste" user "Package Geometry/Pastemask Bottom")
		(5 "F.SilkS" user "Ref Des/Silkscreen Top")
		(7 "B.SilkS" user "Ref Des/Silkscreen Bottom")
		(1 "F.Mask" user "Board Geometry/Soldermask Top")
		(3 "B.Mask" user "Board Geometry/Soldermask Bottom")
		(17 "Dwgs.User" user "User.Drawings")
		(19 "Cmts.User" user "User.Comments")
		(21 "Eco1.User" user "User.Eco1")
		(23 "Eco2.User" user "User.Eco2")
		(25 "Edge.Cuts" user "Board Geometry/Outline")
		(27 "Margin" user)
		(31 "F.CrtYd" user "Package Geometry/Place Bound Top")
		(29 "B.CrtYd" user "Package Geometry/Place Bound Bottom")
		(35 "F.Fab" user "Ref Des/Assembly Top")
		(33 "B.Fab" user "Ref Des/Assembly Bottom")
	)
	(footprint ""
		(layer "F.Cu")
		(at 315.651896 -339.852762 90)
		(property "Reference" "PC114_3"
			(at 0 0 90)
			(layer "F.SilkS")
			(hide yes)
			(effects
				(font
					(size 1.27 1.27)
				)
			)
		)
		(property "Value" ""
			(at 0 0 90)
			(layer "F.Fab")
			(effects
				(font
					(size 1.27 1.27)
				)
			)
		)
		(duplicate_pad_numbers_are_jumpers no)
		(fp_line
			(start 0.7874 -0.4064)
			(end 0.7874 0.4064)
			(stroke
				(width 0.1524)
				(type default)
			)
			(layer "F.SilkS")
		)
		(fp_line
			(start -0.7874 -0.4064)
			(end 0.7874 -0.4064)
			(stroke
				(width 0.1524)
				(type default)
			)
			(layer "F.SilkS")
		)
		(fp_line
			(start 0.7874 0.4064)
			(end -0.7874 0.4064)
			(stroke
				(width 0.1524)
				(type default)
			)
			(layer "F.SilkS")
		)
		(fp_line
			(start -0.7874 0.4064)
			(end -0.7874 -0.4064)
			(stroke
				(width 0.1524)
				(type default)
			)
			(layer "F.SilkS")
		)
		(fp_line
			(start -0.12065 -0.305054)
			(end -0.12065 -0.2794)
			(stroke
				(width 0.1)
				(type default)
			)
			(layer "F.Fab")
		)
		(fp_line
			(start -0.67945 -0.305054)
			(end -0.12065 -0.305054)
			(stroke
				(width 0.1)
				(type default)
			)
			(layer "F.Fab")
		)
		(fp_line
			(start 0.67945 -0.3048)
			(end 0.67945 0.3048)
			(stroke
				(width 0.1)
				(type default)
			)
			(layer "F.Fab")
		)
		(fp_line
			(start 0.12065 -0.3048)
			(end 0.67945 -0.3048)
			(stroke
				(width 0.1)
				(type default)
			)
			(layer "F.Fab")
		)
		(fp_line
			(start 0.12065 -0.2794)
			(end 0.12065 -0.3048)
			(stroke
				(width 0.1)
				(type default)
			)
			(layer "F.Fab")
		)
		(fp_line
			(start -0.12065 -0.2794)
			(end 0.12065 -0.2794)
			(stroke
				(width 0.1)
				(type default)
			)
			(layer "F.Fab")
		)
		(fp_line
			(start 0.120396 0.2794)
			(end -0.12065 0.2794)
			(stroke
				(width 0.1)
				(type default)
			)
			(layer "F.Fab")
		)
		(fp_line
			(start -0.12065 0.2794)
			(end -0.12065 0.3048)
			(stroke
				(width 0.1)
				(type default)
			)
			(layer "F.Fab")
		)
		(fp_line
			(start 0.67945 0.3048)
			(end 0.120396 0.3048)
			(stroke
				(width 0.1)
				(type default)
			)
			(layer "F.Fab")
		)
		(fp_line
			(start 0.120396 0.3048)
			(end 0.120396 0.2794)
			(stroke
				(width 0.1)
				(type default)
			)
			(layer "F.Fab")
		)
		(fp_line
			(start -0.12065 0.3048)
			(end -0.67945 0.3048)
			(stroke
				(width 0.1)
				(type default)
			)
			(layer "F.Fab")
		)
		(fp_line
			(start -0.67945 0.3048)
			(end -0.67945 -0.305054)
			(stroke
				(width 0.1)
				(type default)
			)
			(layer "F.Fab")
		)
		(pad "1" smd circle
			(at -0.40005 0 90)
			(size 0 0)
			(layers "F.Cu" "F.Mask" "F.Paste")
			(net "PVDDCR_CPU1_P0_VCCS")
		)
		(pad "2" smd circle
			(at 0.40005 0 90)
			(size 0 0)
			(layers "F.Cu" "F.Mask" "F.Paste")
			(net "GND")
		)
	)
	(footprint ""
		(layer "F.Cu")
		(at 190.43269 -41.011602 180)
		(property "Reference" "R3997"
			(at 0 0 180)
			(layer "F.SilkS")
			(hide yes)
			(effects
				(font
					(size 1.27 1.27)
				)
			)
		)
		(property "Value" ""
			(at 0 0 180)
			(layer "F.Fab")
			(effects
				(font
					(size 1.27 1.27)
				)
			)
		)
		(duplicate_pad_numbers_are_jumpers no)
		(fp_line
			(start 0.7874 0.4064)
			(end -0.7874 0.4064)
			(stroke
				(width 0.1524)
				(type default)
			)
			(layer "F.SilkS")
		)
		(fp_line
			(start 0.7874 -0.4064)
			(end 0.7874 0.4064)
			(stroke
				(width 0.1524)
				(type default)
			)
			(layer "F.SilkS")
		)
		(fp_line
			(start -0.7874 0.4064)
			(end -0.7874 -0.4064)
			(stroke
				(width 0.1524)
				(type default)
			)
			(layer "F.SilkS")
		)
		(fp_line
			(start -0.7874 -0.4064)
			(end 0.7874 -0.4064)
			(stroke
				(width 0.1524)
				(type default)
			)
			(layer "F.SilkS")
		)
		(fp_line
			(start 0.67945 0.3048)
			(end 0.120396 0.3048)
			(stroke
				(width 0.1)
				(type default)
			)
			(layer "F.Fab")
		)
		(fp_line
			(start 0.67945 -0.3048)
			(end 0.67945 0.3048)
			(stroke
				(width 0.1)
				(type default)
			)
			(layer "F.Fab")
		)
		(fp_line
			(start 0.12065 -0.2794)
			(end 0.12065 -0.3048)
			(stroke
				(width 0.1)
				(type default)
			)
			(layer "F.Fab")
		)
		(fp_line
			(start 0.12065 -0.3048)
			(end 0.67945 -0.3048)
			(stroke
				(width 0.1)
				(type default)
			)
			(layer "F.Fab")
		)
		(fp_line
			(start 0.120396 0.3048)
			(end 0.120396 0.2794)
			(stroke
				(width 0.1)
				(type default)
			)
			(layer "F.Fab")
		)
		(fp_line
			(start 0.120396 0.2794)
			(end -0.12065 0.2794)
			(stroke
				(width 0.1)
				(type default)
			)
			(layer "F.Fab")
		)
		(fp_line
			(start -0.12065 0.3048)
			(end -0.67945 0.3048)
			(stroke
				(width 0.1)
				(type default)
			)
			(layer "F.Fab")
		)
		(fp_line
			(start -0.12065 0.2794)
			(end -0.12065 0.3048)
			(stroke
				(width 0.1)
				(type default)
			)
			(layer "F.Fab")
		)
		(fp_line
			(start -0.12065 -0.2794)
			(end 0.12065 -0.2794)
			(stroke
				(width 0.1)
				(type default)
			)
			(layer "F.Fab")
		)
		(fp_line
			(start -0.12065 -0.305054)
			(end -0.12065 -0.2794)
			(stroke
				(width 0.1)
				(type default)
			)
			(layer "F.Fab")
		)
		(fp_line
			(start -0.67945 0.3048)
			(end -0.67945 -0.305054)
			(stroke
				(width 0.1)
				(type default)
			)
			(layer "F.Fab")
		)
		(fp_line
			(start -0.67945 -0.305054)
			(end -0.12065 -0.305054)
			(stroke
				(width 0.1)
				(type default)
			)
			(layer "F.Fab")
		)
		(pad "1" smd circle
			(at -0.40005 0 180)
			(size 0 0)
			(layers "F.Cu" "F.Mask" "F.Paste")
			(net "P12V_SCM_UV_R")
		)
		(pad "2" smd circle
			(at 0.40005 0 180)
			(size 0 0)
			(layers "F.Cu" "F.Mask" "F.Paste")
			(net "P12V_SCM_UV")
		)
	)
	(footprint ""
		(layer "F.Cu")
		(at 264.478516 -133.622796 180)
		(property "Reference" "R601"
			(at 0 0 180)
			(layer "F.SilkS")
			(hide yes)
			(effects
				(font
					(size 1.27 1.27)
				)
			)
		)
		(property "Value" ""
			(at 0 0 180)
			(layer "F.Fab")
			(effects
				(font
					(size 1.27 1.27)
				)
			)
		)
		(duplicate_pad_numbers_are_jumpers no)
		(fp_line
			(start 0.7874 0.4064)
			(end -0.7874 0.4064)
			(stroke
				(width 0.1524)
				(type default)
			)
			(layer "F.SilkS")
		)
		(fp_line
			(start 0.7874 -0.4064)
			(end 0.7874 0.4064)
			(stroke
				(width 0.1524)
				(type default)
			)
			(layer "F.SilkS")
		)
		(fp_line
			(start -0.7874 0.4064)
			(end -0.7874 -0.4064)
			(stroke
				(width 0.1524)
				(type default)
			)
			(layer "F.SilkS")
		)
		(fp_line
			(start -0.7874 -0.4064)
			(end 0.7874 -0.4064)
			(stroke
				(width 0.1524)
				(type default)
			)
			(layer "F.SilkS")
		)
		(fp_line
			(start 0.67945 0.3048)
			(end 0.120396 0.3048)
			(stroke
				(width 0.1)
				(type default)
			)
			(layer "F.Fab")
		)
		(fp_line
			(start 0.67945 -0.3048)
			(end 0.67945 0.3048)
			(stroke
				(width 0.1)
				(type default)
			)
			(layer "F.Fab")
		)
		(fp_line
			(start 0.12065 -0.2794)
			(end 0.12065 -0.3048)
			(stroke
				(width 0.1)
				(type default)
			)
			(layer "F.Fab")
		)
		(fp_line
			(start 0.12065 -0.3048)
			(end 0.67945 -0.3048)
			(stroke
				(width 0.1)
				(type default)
			)
			(layer "F.Fab")
		)
		(fp_line
			(start 0.120396 0.3048)
			(end 0.120396 0.2794)
			(stroke
				(width 0.1)
				(type default)
			)
			(layer "F.Fab")
		)
		(fp_line
			(start 0.120396 0.2794)
			(end -0.12065 0.2794)
			(stroke
				(width 0.1)
				(type default)
			)
			(layer "F.Fab")
		)
		(fp_line
			(start -0.12065 0.3048)
			(end -0.67945 0.3048)
			(stroke
				(width 0.1)
				(type default)
			)
			(layer "F.Fab")
		)
		(fp_line
			(start -0.12065 0.2794)
			(end -0.12065 0.3048)
			(stroke
				(width 0.1)
				(type default)
			)
			(layer "F.Fab")
		)
		(fp_line
			(start -0.12065 -0.2794)
			(end 0.12065 -0.2794)
			(stroke
				(width 0.1)
				(type default)
			)
			(layer "F.Fab")
		)
		(fp_line
			(start -0.12065 -0.305054)
			(end -0.12065 -0.2794)
			(stroke
				(width 0.1)
				(type default)
			)
			(layer "F.Fab")
		)
		(fp_line
			(start -0.67945 0.3048)
			(end -0.67945 -0.305054)
			(stroke
				(width 0.1)
				(type default)
			)
			(layer "F.Fab")
		)
		(fp_line
			(start -0.67945 -0.305054)
			(end -0.12065 -0.305054)
			(stroke
				(width 0.1)
				(type default)
			)
			(layer "F.Fab")
		)
		(pad "1" smd circle
			(at -0.40005 0 180)
			(size 0 0)
			(layers "F.Cu" "F.Mask" "F.Paste")
			(net "PVDD18_S5_P0")
		)
		(pad "2" smd circle
			(at 0.40005 0 180)
			(size 0 0)
			(layers "F.Cu" "F.Mask" "F.Paste")
			(net "SPI_CPU0_CS1_N")
		)
	)
	(footprint ""
		(layer "F.Cu")
		(at 64.591438 -31.887922 90)
		(property "Reference" "PC2167"
			(at 0 0 90)
			(layer "F.SilkS")
			(hide yes)
			(effects
				(font
					(size 1.27 1.27)
				)
			)
		)
		(property "Value" ""
			(at 0 0 90)
			(layer "F.Fab")
			(effects
				(font
					(size 1.27 1.27)
				)
			)
		)
		(duplicate_pad_numbers_are_jumpers no)
		(fp_line
			(start 0.7874 -0.4064)
			(end 0.7874 0.4064)
			(stroke
				(width 0.1524)
				(type default)
			)
			(layer "F.SilkS")
		)
		(fp_line
			(start -0.7874 -0.4064)
			(end 0.7874 -0.4064)
			(stroke
				(width 0.1524)
				(type default)
			)
			(layer "F.SilkS")
		)
		(fp_line
			(start 0.7874 0.4064)
			(end -0.7874 0.4064)
			(stroke
				(width 0.1524)
				(type default)
			)
			(layer "F.SilkS")
		)
		(fp_line
			(start -0.7874 0.4064)
			(end -0.7874 -0.4064)
			(stroke
				(width 0.1524)
				(type default)
			)
			(layer "F.SilkS")
		)
		(fp_line
			(start -0.12065 -0.305054)
			(end -0.12065 -0.2794)
			(stroke
				(width 0.1)
				(type default)
			)
			(layer "F.Fab")
		)
		(fp_line
			(start -0.67945 -0.305054)
			(end -0.12065 -0.305054)
			(stroke
				(width 0.1)
				(type default)
			)
			(layer "F.Fab")
		)
		(fp_line
			(start 0.67945 -0.3048)
			(end 0.67945 0.3048)
			(stroke
				(width 0.1)
				(type default)
			)
			(layer "F.Fab")
		)
		(fp_line
			(start 0.12065 -0.3048)
			(end 0.67945 -0.3048)
			(stroke
				(width 0.1)
				(type default)
			)
			(layer "F.Fab")
		)
		(fp_line
			(start 0.12065 -0.2794)
			(end 0.12065 -0.3048)
			(stroke
				(width 0.1)
				(type default)
			)
			(layer "F.Fab")
		)
		(fp_line
			(start -0.12065 -0.2794)
			(end 0.12065 -0.2794)
			(stroke
				(width 0.1)
				(type default)
			)
			(layer "F.Fab")
		)
		(fp_line
			(start 0.120396 0.2794)
			(end -0.12065 0.2794)
			(stroke
				(width 0.1)
				(type default)
			)
			(layer "F.Fab")
		)
		(fp_line
			(start -0.12065 0.2794)
			(end -0.12065 0.3048)
			(stroke
				(width 0.1)
				(type default)
			)
			(layer "F.Fab")
		)
		(fp_line
			(start 0.67945 0.3048)
			(end 0.120396 0.3048)
			(stroke
				(width 0.1)
				(type default)
			)
			(layer "F.Fab")
		)
		(fp_line
			(start 0.120396 0.3048)
			(end 0.120396 0.2794)
			(stroke
				(width 0.1)
				(type default)
			)
			(layer "F.Fab")
		)
		(fp_line
			(start -0.12065 0.3048)
			(end -0.67945 0.3048)
			(stroke
				(width 0.1)
				(type default)
			)
			(layer "F.Fab")
		)
		(fp_line
			(start -0.67945 0.3048)
			(end -0.67945 -0.305054)
			(stroke
				(width 0.1)
				(type default)
			)
			(layer "F.Fab")
		)
		(pad "1" smd circle
			(at -0.40005 0 90)
			(size 0 0)
			(layers "F.Cu" "F.Mask" "F.Paste")
			(net "P12V_OCP_IMON_2")
		)
		(pad "2" smd circle
			(at 0.40005 0 90)
			(size 0 0)
			(layers "F.Cu" "F.Mask" "F.Paste")
			(net "GND")
		)
	)
	(footprint ""
		(layer "F.Cu")
		(at 94.14891 -340.240874)
		(property "Reference" "PR270"
			(at 0 0 0)
			(layer "F.SilkS")
			(hide yes)
			(effects
				(font
					(size 1.27 1.27)
				)
			)
		)
		(property "Value" ""
			(at 0 0 0)
			(layer "F.Fab")
			(effects
				(font
					(size 1.27 1.27)
				)
			)
		)
		(duplicate_pad_numbers_are_jumpers no)
		(fp_line
			(start -0.7874 -0.4064)
			(end 0.7874 -0.4064)
			(stroke
				(width 0.1524)
				(type default)
			)
			(layer "F.SilkS")
		)
		(fp_line
			(start -0.7874 0.4064)
			(end -0.7874 -0.4064)
			(stroke
				(width 0.1524)
				(type default)
			)
			(layer "F.SilkS")
		)
		(fp_line
			(start 0.7874 -0.4064)
			(end 0.7874 0.4064)
			(stroke
				(width 0.1524)
				(type default)
			)
			(layer "F.SilkS")
		)
		(fp_line
			(start 0.7874 0.4064)
			(end -0.7874 0.4064)
			(stroke
				(width 0.1524)
				(type default)
			)
			(layer "F.SilkS")
		)
		(fp_line
			(start -0.67945 -0.305054)
			(end -0.12065 -0.305054)
			(stroke
				(width 0.1)
				(type default)
			)
			(layer "F.Fab")
		)
		(fp_line
			(start -0.67945 0.3048)
			(end -0.67945 -0.305054)
			(stroke
				(width 0.1)
				(type default)
			)
			(layer "F.Fab")
		)
		(fp_line
			(start -0.12065 -0.305054)
			(end -0.12065 -0.2794)
			(stroke
				(width 0.1)
				(type default)
			)
			(layer "F.Fab")
		)
		(fp_line
			(start -0.12065 -0.2794)
			(end 0.12065 -0.2794)
			(stroke
				(width 0.1)
				(type default)
			)
			(layer "F.Fab")
		)
		(fp_line
			(start -0.12065 0.2794)
			(end -0.12065 0.3048)
			(stroke
				(width 0.1)
				(type default)
			)
			(layer "F.Fab")
		)
		(fp_line
			(start -0.12065 0.3048)
			(end -0.67945 0.3048)
			(stroke
				(width 0.1)
				(type default)
			)
			(layer "F.Fab")
		)
		(fp_line
			(start 0.120396 0.2794)
			(end -0.12065 0.2794)
			(stroke
				(width 0.1)
				(type default)
			)
			(layer "F.Fab")
		)
		(fp_line
			(start 0.120396 0.3048)
			(end 0.120396 0.2794)
			(stroke
				(width 0.1)
				(type default)
			)
			(layer "F.Fab")
		)
		(fp_line
			(start 0.12065 -0.3048)
			(end 0.67945 -0.3048)
			(stroke
				(width 0.1)
				(type default)
			)
			(layer "F.Fab")
		)
		(fp_line
			(start 0.12065 -0.2794)
			(end 0.12065 -0.3048)
			(stroke
				(width 0.1)
				(type default)
			)
			(layer "F.Fab")
		)
		(fp_line
			(start 0.67945 -0.3048)
			(end 0.67945 0.3048)
			(stroke
				(width 0.1)
				(type default)
			)
			(layer "F.Fab")
		)
		(fp_line
			(start 0.67945 0.3048)
			(end 0.120396 0.3048)
			(stroke
				(width 0.1)
				(type default)
			)
			(layer "F.Fab")
		)
		(pad "1" smd circle
			(at -0.40005 0)
			(size 0 0)
			(layers "F.Cu" "F.Mask" "F.Paste")
			(net "PVDDCR_CPU1_P1_LSET5")
		)
		(pad "2" smd circle
			(at 0.40005 0)
			(size 0 0)
			(layers "F.Cu" "F.Mask" "F.Paste")
			(net "GND")
		)
	)
	(footprint ""
		(layer "F.Cu")
		(at 321.106546 -100.36175 180)
		(property "Reference" "R1326"
			(at 0 0 180)
			(layer "F.SilkS")
			(hide yes)
			(effects
				(font
					(size 1.27 1.27)
				)
			)
		)
		(property "Value" ""
			(at 0 0 180)
			(layer "F.Fab")
			(effects
				(font
					(size 1.27 1.27)
				)
			)
		)
		(duplicate_pad_numbers_are_jumpers no)
		(fp_line
			(start 0.7874 0.4064)
			(end -0.7874 0.4064)
			(stroke
				(width 0.1524)
				(type default)
			)
			(layer "F.SilkS")
		)
		(fp_line
			(start 0.7874 -0.4064)
			(end 0.7874 0.4064)
			(stroke
				(width 0.1524)
				(type default)
			)
			(layer "F.SilkS")
		)
		(fp_line
			(start -0.7874 0.4064)
			(end -0.7874 -0.4064)
			(stroke
				(width 0.1524)
				(type default)
			)
			(layer "F.SilkS")
		)
		(fp_line
			(start -0.7874 -0.4064)
			(end 0.7874 -0.4064)
			(stroke
				(width 0.1524)
				(type default)
			)
			(layer "F.SilkS")
		)
		(fp_line
			(start 0.67945 0.3048)
			(end 0.120396 0.3048)
			(stroke
				(width 0.1)
				(type default)
			)
			(layer "F.Fab")
		)
		(fp_line
			(start 0.67945 -0.3048)
			(end 0.67945 0.3048)
			(stroke
				(width 0.1)
				(type default)
			)
			(layer "F.Fab")
		)
		(fp_line
			(start 0.12065 -0.2794)
			(end 0.12065 -0.3048)
			(stroke
				(width 0.1)
				(type default)
			)
			(layer "F.Fab")
		)
		(fp_line
			(start 0.12065 -0.3048)
			(end 0.67945 -0.3048)
			(stroke
				(width 0.1)
				(type default)
			)
			(layer "F.Fab")
		)
		(fp_line
			(start 0.120396 0.3048)
			(end 0.120396 0.2794)
			(stroke
				(width 0.1)
				(type default)
			)
			(layer "F.Fab")
		)
		(fp_line
			(start 0.120396 0.2794)
			(end -0.12065 0.2794)
			(stroke
				(width 0.1)
				(type default)
			)
			(layer "F.Fab")
		)
		(fp_line
			(start -0.12065 0.3048)
			(end -0.67945 0.3048)
			(stroke
				(width 0.1)
				(type default)
			)
			(layer "F.Fab")
		)
		(fp_line
			(start -0.12065 0.2794)
			(end -0.12065 0.3048)
			(stroke
				(width 0.1)
				(type default)
			)
			(layer "F.Fab")
		)
		(fp_line
			(start -0.12065 -0.2794)
			(end 0.12065 -0.2794)
			(stroke
				(width 0.1)
				(type default)
			)
			(layer "F.Fab")
		)
		(fp_line
			(start -0.12065 -0.305054)
			(end -0.12065 -0.2794)
			(stroke
				(width 0.1)
				(type default)
			)
			(layer "F.Fab")
		)
		(fp_line
			(start -0.67945 0.3048)
			(end -0.67945 -0.305054)
			(stroke
				(width 0.1)
				(type default)
			)
			(layer "F.Fab")
		)
		(fp_line
			(start -0.67945 -0.305054)
			(end -0.12065 -0.305054)
			(stroke
				(width 0.1)
				(type default)
			)
			(layer "F.Fab")
		)
		(pad "1" smd circle
			(at -0.40005 0 180)
			(size 0 0)
			(layers "F.Cu" "F.Mask" "F.Paste")
			(net "P3V3_AUX")
		)
		(pad "2" smd circle
			(at 0.40005 0 180)
			(size 0 0)
			(layers "F.Cu" "F.Mask" "F.Paste")
			(net "E1S_0_P3V3_P12V_ADC_R_ALERT")
		)
	)
	(footprint ""
		(layer "F.Cu")
		(at 98.555302 -370.57203 -90)
		(property "Reference" "C716"
			(at 0 0 270)
			(layer "F.SilkS")
			(hide yes)
			(effects
				(font
					(size 1.27 1.27)
				)
			)
		)
		(property "Value" ""
			(at 0 0 270)
			(layer "F.Fab")
			(effects
				(font
					(size 1.27 1.27)
				)
			)
		)
		(duplicate_pad_numbers_are_jumpers no)
		(fp_line
			(start -0.299974 0.150114)
			(end -0.299974 -0.150114)
			(stroke
				(width 0.1)
				(type default)
			)
			(layer "F.Fab")
		)
		(fp_line
			(start 0.299974 0.150114)
			(end -0.299974 0.150114)
			(stroke
				(width 0.1)
				(type default)
			)
			(layer "F.Fab")
		)
		(fp_line
			(start -0.299974 -0.150114)
			(end 0.299974 -0.150114)
			(stroke
				(width 0.1)
				(type default)
			)
			(layer "F.Fab")
		)
		(fp_line
			(start 0.299974 -0.150114)
			(end 0.299974 0.150114)
			(stroke
				(width 0.1)
				(type default)
			)
			(layer "F.Fab")
		)
		(pad "1" smd rect
			(at -0.2667 0 270)
			(size 0.3048 0.381)
			(layers "F.Cu" "F.Mask" "F.Paste")
			(net "P5E_CPU1_P1_TX_C_DN<12>")
		)
		(pad "2" smd rect
			(at 0.2667 0 270)
			(size 0.3048 0.381)
			(layers "F.Cu" "F.Mask" "F.Paste")
			(net "P5E_CPU1_P1_TX_DN<12>")
		)
	)
)
